(kicad_pcb
	(version 20260206)
	(generator "pcbnew")
	(generator_version "10.0")
	(general
		(thickness 1.6)
		(legacy_teardrops no)
	)
	(paper "A4")
	(title_block
		(title "baseboard — 13948-1b.1110WZS1818.brd")
		(comment 1 "Honey Badger (Wiwynn) / footprint 1028 of 2523 (U40), pads 345-408 of 408")
	)
	(layers
		(0 "F.Cu" signal "TOP")
		(4 "In1.Cu" signal "L2GND")
		(6 "In2.Cu" signal "L3")
		(8 "In3.Cu" signal "L4VCC")
		(10 "In4.Cu" signal "L5VCC")
		(12 "In5.Cu" signal "L6")
		(14 "In6.Cu" signal "L7GND")
		(2 "B.Cu" signal "BOTTOM")
		(9 "F.Adhes" user "F.Adhesive")
		(11 "B.Adhes" user "B.Adhesive")
		(13 "F.Paste" user "Package Geometry/Pastemask Top")
		(15 "B.Paste" user "Package Geometry/Pastemask Bottom")
		(5 "F.SilkS" user "Ref Des/Silkscreen Top")
		(7 "B.SilkS" user "Ref Des/Silkscreen Bottom")
		(1 "F.Mask" user "Board Geometry/Soldermask Top")
		(3 "B.Mask" user "Board Geometry/Soldermask Bottom")
		(17 "Dwgs.User" user "User.Drawings")
		(19 "Cmts.User" user "User.Comments")
		(21 "Eco1.User" user "User.Eco1")
		(23 "Eco2.User" user "User.Eco2")
		(25 "Edge.Cuts" user "Board Geometry/Outline")
		(27 "Margin" user)
		(31 "F.CrtYd" user "Package Geometry/Place Bound Top")
		(29 "B.CrtYd" user "Package Geometry/Place Bound Bottom")
		(35 "F.Fab" user "Ref Des/Assembly Top")
		(33 "B.Fab" user "Ref Des/Assembly Bottom")
	)
	(footprint ""
		(layer "F.Cu")
		(at 293.234872 -175.840136 180)
		(property "Reference" "U40"
			(at 0 0 180)
			(layer "F.SilkS")
			(hide yes)
			(effects
				(font
					(size 1.27 1.27)
				)
			)
		)
		(property "Value" "AST1250A1-GP"
			(at -17.7292 -6.184392 180)
			(unlocked yes)
			(layer "F.Fab")
			(hide yes)
			(effects
				(font
					(size 1.016 1.016)
					(thickness 0.1524)
				)
			)
		)
		(property "Device Type" "BGA408D19H52"
			(at -17.7292 -7.708392 180)
			(unlocked yes)
			(layer "F.Fab")
			(hide yes)
			(effects
				(font
					(size 1.016 1.016)
					(thickness 0.1524)
				)
			)
		)
		(duplicate_pad_numbers_are_jumpers no)
		(pad "V3" smd circle
			(at -6.800088 5.199888 180)
			(size 0.3556 0.3556)
			(layers "F.Cu" "F.Mask" "F.Paste")
			(net "TP_BMC_GPIOM0")
		)
		(pad "V4" smd circle
			(at -5.999988 5.199888 180)
			(size 0.3556 0.3556)
			(layers "F.Cu" "F.Mask" "F.Paste")
			(net "TP_BMC_GPIOM3")
		)
		(pad "V5" smd circle
			(at -5.199888 5.199888 180)
			(size 0.3556 0.3556)
			(layers "F.Cu" "F.Mask" "F.Paste")
			(net "TP_BMC_GPIOM7")
		)
		(pad "V6" smd circle
			(at -4.400042 5.199888 180)
			(size 0.3556 0.3556)
			(layers "F.Cu" "F.Mask" "F.Paste")
			(net "HB0_R_IN0")
		)
		(pad "V7" smd circle
			(at -3.599942 5.199888 180)
			(size 0.3556 0.3556)
			(layers "F.Cu" "F.Mask" "F.Paste")
			(net "TP_BMC_GPIOO7")
		)
		(pad "V8" smd circle
			(at -2.800096 5.199888 180)
			(size 0.3556 0.3556)
			(layers "F.Cu" "F.Mask" "F.Paste")
			(net "MEMDM_1")
		)
		(pad "V9" smd circle
			(at -1.999996 5.199888 180)
			(size 0.3556 0.3556)
			(layers "F.Cu" "F.Mask" "F.Paste")
			(net "MEMDQ_13")
		)
		(pad "V10" smd circle
			(at -1.199896 5.199888 180)
			(size 0.3556 0.3556)
			(layers "F.Cu" "F.Mask" "F.Paste")
			(net "MEMDQ_8")
		)
		(pad "V11" smd circle
			(at -0.40005 5.199888 180)
			(size 0.3556 0.3556)
			(layers "F.Cu" "F.Mask" "F.Paste")
			(net "MEMDQ_6")
		)
		(pad "V12" smd circle
			(at 0.40005 5.199888 180)
			(size 0.3556 0.3556)
			(layers "F.Cu" "F.Mask" "F.Paste")
			(net "MEMDQ_1")
		)
		(pad "V13" smd circle
			(at 1.199896 5.199888 180)
			(size 0.3556 0.3556)
			(layers "F.Cu" "F.Mask" "F.Paste")
			(net "DDR_VREF")
		)
		(pad "V14" smd circle
			(at 1.999996 5.199888 180)
			(size 0.3556 0.3556)
			(layers "F.Cu" "F.Mask" "F.Paste")
			(net "MEMODT")
		)
		(pad "V15" smd circle
			(at 2.800096 5.199888 180)
			(size 0.3556 0.3556)
			(layers "F.Cu" "F.Mask" "F.Paste")
			(net "MEMA_2")
		)
		(pad "V16" smd circle
			(at 3.599942 5.199888 180)
			(size 0.3556 0.3556)
			(layers "F.Cu" "F.Mask" "F.Paste")
			(net "Net_1410")
		)
		(pad "V17" smd circle
			(at 4.400042 5.199888 180)
			(size 0.3556 0.3556)
			(layers "F.Cu" "F.Mask" "F.Paste")
			(net "MPLLAV33")
		)
		(pad "V18" smd circle
			(at 5.199888 5.199888 180)
			(size 0.3556 0.3556)
			(layers "F.Cu" "F.Mask" "F.Paste")
			(net "GND")
		)
		(pad "V19" smd circle
			(at 5.999988 5.199888 180)
			(size 0.3556 0.3556)
			(layers "F.Cu" "F.Mask" "F.Paste")
			(net "P1V26_STBY")
		)
		(pad "V20" smd circle
			(at 6.800088 5.199888 180)
			(size 0.3556 0.3556)
			(layers "F.Cu" "F.Mask" "F.Paste")
			(net "FLA_CS_1_R")
		)
		(pad "V21" smd circle
			(at 7.599934 5.199888 180)
			(size 0.3556 0.3556)
			(layers "F.Cu" "F.Mask" "F.Paste")
			(net "TP_BMC_GPIOR4")
		)
		(pad "V22" smd circle
			(at 8.400034 5.199888 180)
			(size 0.3556 0.3556)
			(layers "F.Cu" "F.Mask" "F.Paste")
			(net "ROMD6")
		)
		(pad "W1" smd circle
			(at -8.400034 5.999988 180)
			(size 0.3556 0.3556)
			(layers "F.Cu" "F.Mask" "F.Paste")
			(net "TP_BMC_GPIOL6")
		)
		(pad "W2" smd circle
			(at -7.599934 5.999988 180)
			(size 0.3556 0.3556)
			(layers "F.Cu" "F.Mask" "F.Paste")
			(net "TP_BMC_GPIOM1")
		)
		(pad "W3" smd circle
			(at -6.800088 5.999988 180)
			(size 0.3556 0.3556)
			(layers "F.Cu" "F.Mask" "F.Paste")
			(net "TP_BMC_GPIOM4")
		)
		(pad "W4" smd circle
			(at -5.999988 5.999988 180)
			(size 0.3556 0.3556)
			(layers "F.Cu" "F.Mask" "F.Paste")
			(net "FAN_PWM_PCIE_BMC")
		)
		(pad "W5" smd circle
			(at -5.199888 5.999988 180)
			(size 0.3556 0.3556)
			(layers "F.Cu" "F.Mask" "F.Paste")
			(net "BMC_SELF_TRAY")
		)
		(pad "W6" smd circle
			(at -4.400042 5.999988 180)
			(size 0.3556 0.3556)
			(layers "F.Cu" "F.Mask" "F.Paste")
			(net "HB_EXP_TO_BMC")
		)
		(pad "W7" smd circle
			(at -3.599942 5.999988 180)
			(size 0.3556 0.3556)
			(layers "F.Cu" "F.Mask" "F.Paste")
			(net "BMC0_TACH10")
		)
		(pad "W8" smd circle
			(at -2.800096 5.999988 180)
			(size 0.3556 0.3556)
			(layers "F.Cu" "F.Mask" "F.Paste")
			(net "MEMDQ_15")
		)
		(pad "W9" smd circle
			(at -1.999996 5.999988 180)
			(size 0.3556 0.3556)
			(layers "F.Cu" "F.Mask" "F.Paste")
			(net "MEMDQ_12")
		)
		(pad "W10" smd circle
			(at -1.199896 5.999988 180)
			(size 0.3556 0.3556)
			(layers "F.Cu" "F.Mask" "F.Paste")
			(net "MEMDM_0")
		)
		(pad "W11" smd circle
			(at -0.40005 5.999988 180)
			(size 0.3556 0.3556)
			(layers "F.Cu" "F.Mask" "F.Paste")
			(net "MEMDQ_5")
		)
		(pad "W12" smd circle
			(at 0.40005 5.999988 180)
			(size 0.3556 0.3556)
			(layers "F.Cu" "F.Mask" "F.Paste")
			(net "MEMDQ_0")
		)
		(pad "W13" smd circle
			(at 1.199896 5.999988 180)
			(size 0.3556 0.3556)
			(layers "F.Cu" "F.Mask" "F.Paste")
			(net "MEMRASN")
		)
		(pad "W14" smd circle
			(at 1.999996 5.999988 180)
			(size 0.3556 0.3556)
			(layers "F.Cu" "F.Mask" "F.Paste")
			(net "MEMBA_0")
		)
		(pad "W15" smd circle
			(at 2.800096 5.999988 180)
			(size 0.3556 0.3556)
			(layers "F.Cu" "F.Mask" "F.Paste")
			(net "MEMA_1")
		)
		(pad "W16" smd circle
			(at 3.599942 5.999988 180)
			(size 0.3556 0.3556)
			(layers "F.Cu" "F.Mask" "F.Paste")
			(net "MEMA_5")
		)
		(pad "W17" smd circle
			(at 4.400042 5.999988 180)
			(size 0.3556 0.3556)
			(layers "F.Cu" "F.Mask" "F.Paste")
			(net "MEMA_12")
		)
		(pad "W18" smd circle
			(at 5.199888 5.999988 180)
			(size 0.3556 0.3556)
			(layers "F.Cu" "F.Mask" "F.Paste")
			(net "P3V3_STBY")
		)
		(pad "W19" smd circle
			(at 5.999988 5.999988 180)
			(size 0.3556 0.3556)
			(layers "F.Cu" "F.Mask" "F.Paste")
			(net "V1PLLAV12")
		)
		(pad "W20" smd circle
			(at 6.800088 5.999988 180)
			(size 0.3556 0.3556)
			(layers "F.Cu" "F.Mask" "F.Paste")
			(net "BMC0_SRST_N")
		)
		(pad "W21" smd circle
			(at 7.599934 5.999988 180)
			(size 0.3556 0.3556)
			(layers "F.Cu" "F.Mask" "F.Paste")
			(net "TP_BMC_GPIOR1")
		)
		(pad "W22" smd circle
			(at 8.400034 5.999988 180)
			(size 0.3556 0.3556)
			(layers "F.Cu" "F.Mask" "F.Paste")
			(net "TP_BMC_GPIOR5")
		)
		(pad "Y1" smd circle
			(at -8.400034 6.800088 180)
			(size 0.4064 0.4064)
			(layers "F.Cu" "F.Mask" "F.Paste")
			(net "TP_BMC_GPIOM2")
		)
		(pad "Y2" smd circle
			(at -7.599934 6.800088 180)
			(size 0.4064 0.4064)
			(layers "F.Cu" "F.Mask" "F.Paste")
			(net "TP_BMC_GPIOM5")
		)
		(pad "Y3" smd circle
			(at -6.800088 6.800088 180)
			(size 0.4064 0.4064)
			(layers "F.Cu" "F.Mask" "F.Paste")
			(net "BMC_FW_DET_BOARD_VER_0")
		)
		(pad "Y4" smd circle
			(at -5.999988 6.800088 180)
			(size 0.3556 0.3556)
			(layers "F.Cu" "F.Mask" "F.Paste")
			(net "BMC0_I2C_IO_EXP_RESET#")
		)
		(pad "Y5" smd circle
			(at -5.199888 6.800088 180)
			(size 0.3556 0.3556)
			(layers "F.Cu" "F.Mask" "F.Paste")
			(net "HB0_R_IN1")
		)
		(pad "Y6" smd circle
			(at -4.400042 6.800088 180)
			(size 0.3556 0.3556)
			(layers "F.Cu" "F.Mask" "F.Paste")
			(net "TP_BMC0_TACH8")
		)
		(pad "Y7" smd circle
			(at -3.599942 6.800088 180)
			(size 0.3556 0.3556)
			(layers "F.Cu" "F.Mask" "F.Paste")
			(net "BMC0_TACH13")
		)
		(pad "Y8" smd circle
			(at -2.800096 6.800088 180)
			(size 0.3556 0.3556)
			(layers "F.Cu" "F.Mask" "F.Paste")
			(net "MEMDQ_14")
		)
		(pad "Y9" smd circle
			(at -1.999996 6.800088 180)
			(size 0.3556 0.3556)
			(layers "F.Cu" "F.Mask" "F.Paste")
			(net "MEMDQ_11")
		)
		(pad "Y10" smd circle
			(at -1.199896 6.800088 180)
			(size 0.3556 0.3556)
			(layers "F.Cu" "F.Mask" "F.Paste")
			(net "MEMDQ_7")
		)
		(pad "Y11" smd circle
			(at -0.40005 6.800088 180)
			(size 0.3556 0.3556)
			(layers "F.Cu" "F.Mask" "F.Paste")
			(net "MEMDQ_4")
		)
		(pad "Y12" smd circle
			(at 0.40005 6.800088 180)
			(size 0.3556 0.3556)
			(layers "F.Cu" "F.Mask" "F.Paste")
			(net "MEMCKE")
		)
		(pad "Y13" smd circle
			(at 1.199896 6.800088 180)
			(size 0.3556 0.3556)
			(layers "F.Cu" "F.Mask" "F.Paste")
			(net "MEMWEN")
		)
		(pad "Y14" smd circle
			(at 1.999996 6.800088 180)
			(size 0.3556 0.3556)
			(layers "F.Cu" "F.Mask" "F.Paste")
			(net "MEMBA_2")
		)
		(pad "Y15" smd circle
			(at 2.800096 6.800088 180)
			(size 0.3556 0.3556)
			(layers "F.Cu" "F.Mask" "F.Paste")
			(net "MEMA_10")
		)
		(pad "Y16" smd circle
			(at 3.599942 6.800088 180)
			(size 0.3556 0.3556)
			(layers "F.Cu" "F.Mask" "F.Paste")
			(net "MEMA_3")
		)
		(pad "Y17" smd circle
			(at 4.400042 6.800088 180)
			(size 0.3556 0.3556)
			(layers "F.Cu" "F.Mask" "F.Paste")
			(net "MEMA_13")
		)
		(pad "Y18" smd circle
			(at 5.199888 6.800088 180)
			(size 0.3556 0.3556)
			(layers "F.Cu" "F.Mask" "F.Paste")
			(net "P1V26_STBY")
		)
		(pad "Y19" smd circle
			(at 5.999988 6.800088 180)
			(size 0.3556 0.3556)
			(layers "F.Cu" "F.Mask" "F.Paste")
			(net "GND")
		)
		(pad "Y20" smd circle
			(at 6.800088 6.800088 180)
			(size 0.4064 0.4064)
			(layers "F.Cu" "F.Mask" "F.Paste")
			(net "V1PLLAV12")
		)
		(pad "Y21" smd circle
			(at 7.599934 6.800088 180)
			(size 0.4064 0.4064)
			(layers "F.Cu" "F.Mask" "F.Paste")
			(net "DP_BMC_EXP_RST_N_R")
		)
		(pad "Y22" smd circle
			(at 8.400034 6.800088 180)
			(size 0.4064 0.4064)
			(layers "F.Cu" "F.Mask" "F.Paste")
			(net "TP_BMC_GPIOR2")
		)
	)
)
